(kicad_pcb
	(version 20260206)
	(generator "pcbnew")
	(generator_version "10.0")
	(general
		(thickness 1.6)
		(legacy_teardrops no)
	)
	(paper "A4")
	(title_block
		(title "Wiwynn_Tioga_Pass_MB.brd")
		(comment 1 "Tioga Pass / footprints 3499-3506 of 4770")
	)
	(layers
		(0 "F.Cu" signal "TOP")
		(4 "In1.Cu" signal "L2GND")
		(6 "In2.Cu" signal "L3")
		(8 "In3.Cu" signal "L4GND")
		(10 "In4.Cu" signal "L5")
		(12 "In5.Cu" signal "L6GND")
		(14 "In6.Cu" signal "L7VCC")
		(16 "In7.Cu" signal "L8VCC")
		(18 "In8.Cu" signal "L9GND")
		(20 "In9.Cu" signal "L10")
		(22 "In10.Cu" signal "L11GND")
		(24 "In11.Cu" signal "L12")
		(26 "In12.Cu" signal "L13GND")
		(2 "B.Cu" signal "BOTTOM")
		(9 "F.Adhes" user "F.Adhesive")
		(11 "B.Adhes" user "B.Adhesive")
		(13 "F.Paste" user "Package Geometry/Pastemask Top")
		(15 "B.Paste" user "Package Geometry/Pastemask Bottom")
		(5 "F.SilkS" user "Ref Des/Silkscreen Top")
		(7 "B.SilkS" user "Ref Des/Silkscreen Bottom")
		(1 "F.Mask" user "Board Geometry/Soldermask Top")
		(3 "B.Mask" user "Board Geometry/Soldermask Bottom")
		(17 "Dwgs.User" user "User.Drawings")
		(19 "Cmts.User" user "User.Comments")
		(21 "Eco1.User" user "User.Eco1")
		(23 "Eco2.User" user "User.Eco2")
		(25 "Edge.Cuts" user "Board Geometry/Outline")
		(27 "Margin" user)
		(31 "F.CrtYd" user "Package Geometry/Place Bound Top")
		(29 "B.CrtYd" user "Package Geometry/Place Bound Bottom")
		(35 "F.Fab" user "Ref Des/Assembly Top")
		(33 "B.Fab" user "Ref Des/Assembly Bottom")
	)
	(footprint ""
		(layer "B.Cu")
		(at 18.415 -73.406 180)
		(property "Reference" "C9P16"
			(at 0 0 0)
			(layer "B.SilkS")
			(hide yes)
			(effects
				(font
					(size 1.27 1.27)
				)
				(justify mirror)
			)
		)
		(property "Value" ""
			(at 0 0 0)
			(layer "B.Fab")
			(effects
				(font
					(size 1.27 1.27)
				)
				(justify mirror)
			)
		)
		(duplicate_pad_numbers_are_jumpers no)
		(fp_rect
			(start -0.3048 0.9906)
			(end 0.3048 -0.1016)
			(stroke
				(width 0)
				(type default)
			)
			(fill no)
			(layer "B.CrtYd")
		)
		(fp_line
			(start 0.3048 0.9906)
			(end -0.3048 0.9906)
			(stroke
				(width 0.1)
				(type default)
			)
			(layer "B.Fab")
		)
		(fp_line
			(start 0.3048 -0.1016)
			(end 0.3048 0.9906)
			(stroke
				(width 0.1)
				(type default)
			)
			(layer "B.Fab")
		)
		(fp_line
			(start -0.3048 0.9906)
			(end -0.3048 -0.1016)
			(stroke
				(width 0.1)
				(type default)
			)
			(layer "B.Fab")
		)
		(fp_line
			(start -0.3048 -0.1016)
			(end 0.3048 -0.1016)
			(stroke
				(width 0.1)
				(type default)
			)
			(layer "B.Fab")
		)
		(pad "1" smd rect
			(at 0 0)
			(size 0.508 0.508)
			(layers "B.Cu" "B.Mask" "B.Paste")
			(net "A_HSC_MOP")
		)
		(pad "2" smd rect
			(at 0 0.889)
			(size 0.508 0.508)
			(layers "B.Cu" "B.Mask" "B.Paste")
			(net "AGND_HSC")
		)
		(zone
			(layer "B.Cu")
			(hatch none 0.5)
			(connect_pads
				(clearance 0)
			)
			(min_thickness 0.25)
			(keepout
				(tracks not_allowed)
				(vias allowed)
				(pads allowed)
				(copperpour not_allowed)
				(footprints allowed)
			)
			(placement
				(enabled no)
				(sheetname "")
			)
			(fill
				(thermal_gap 0.5)
				(thermal_bridge_width 0.5)
				(island_removal_mode 0)
			)
			(polygon
				(pts
					(xy 18.669 -74.041) (xy 18.161 -74.041) (xy 18.161 -73.66) (xy 18.669 -73.66)
				)
			)
		)
		(zone
			(layer "B.Cu")
			(hatch none 0.5)
			(connect_pads
				(clearance 0)
			)
			(min_thickness 0.25)
			(keepout
				(tracks allowed)
				(vias not_allowed)
				(pads allowed)
				(copperpour not_allowed)
				(footprints allowed)
			)
			(placement
				(enabled no)
				(sheetname "")
			)
			(fill
				(thermal_gap 0.5)
				(thermal_bridge_width 0.5)
				(island_removal_mode 0)
			)
			(polygon
				(pts
					(xy 18.669 -74.041) (xy 18.161 -74.041) (xy 18.161 -73.66) (xy 18.669 -73.66)
				)
			)
		)
	)
	(footprint ""
		(layer "B.Cu")
		(at 171.196 -87.757)
		(property "Reference" "R6P3"
			(at 0 0 0)
			(layer "B.SilkS")
			(hide yes)
			(effects
				(font
					(size 1.27 1.27)
				)
				(justify mirror)
			)
		)
		(property "Value" ""
			(at 0 0 0)
			(layer "B.Fab")
			(effects
				(font
					(size 1.27 1.27)
				)
				(justify mirror)
			)
		)
		(duplicate_pad_numbers_are_jumpers no)
		(fp_poly
			(pts
				(xy 0.2794 -0.1016) (xy -0.2794 -0.1016) (xy -0.2794 0.9906) (xy 0.2794 0.9906)
			)
			(stroke
				(width 0)
				(type default)
			)
			(fill no)
			(layer "B.CrtYd")
		)
		(fp_line
			(start -0.2794 -0.1016)
			(end 0.2794 -0.1016)
			(stroke
				(width 0.1)
				(type default)
			)
			(layer "B.Fab")
		)
		(fp_line
			(start -0.2794 0.9906)
			(end -0.2794 -0.1016)
			(stroke
				(width 0.1)
				(type default)
			)
			(layer "B.Fab")
		)
		(fp_line
			(start 0.2794 -0.1016)
			(end 0.2794 0.9906)
			(stroke
				(width 0.1)
				(type default)
			)
			(layer "B.Fab")
		)
		(fp_line
			(start 0.2794 0.9906)
			(end -0.2794 0.9906)
			(stroke
				(width 0.1)
				(type default)
			)
			(layer "B.Fab")
		)
		(pad "1" smd rect
			(at 0 0 180)
			(size 0.508 0.508)
			(layers "B.Cu" "B.Mask" "B.Paste")
			(net "CLK_100M_CPU0_RC_REFCLK1_DP")
		)
		(pad "2" smd rect
			(at 0 0.889 180)
			(size 0.508 0.508)
			(layers "B.Cu" "B.Mask" "B.Paste")
			(net "GND")
		)
		(zone
			(layer "B.Cu")
			(hatch none 0.5)
			(connect_pads
				(clearance 0)
			)
			(min_thickness 0.25)
			(keepout
				(tracks allowed)
				(vias not_allowed)
				(pads allowed)
				(copperpour not_allowed)
				(footprints allowed)
			)
			(placement
				(enabled no)
				(sheetname "")
			)
			(fill
				(thermal_gap 0.5)
				(thermal_bridge_width 0.5)
				(island_removal_mode 0)
			)
			(polygon
				(pts
					(xy 171.45 -87.503) (xy 170.942 -87.503) (xy 170.942 -87.122) (xy 171.45 -87.122)
				)
			)
		)
		(zone
			(layer "B.Cu")
			(hatch none 0.5)
			(connect_pads
				(clearance 0)
			)
			(min_thickness 0.25)
			(keepout
				(tracks not_allowed)
				(vias allowed)
				(pads allowed)
				(copperpour not_allowed)
				(footprints allowed)
			)
			(placement
				(enabled no)
				(sheetname "")
			)
			(fill
				(thermal_gap 0.5)
				(thermal_bridge_width 0.5)
				(island_removal_mode 0)
			)
			(polygon
				(pts
					(xy 171.45 -87.122) (xy 170.942 -87.122) (xy 170.942 -87.503) (xy 171.45 -87.503)
				)
			)
		)
	)
	(footprint ""
		(layer "B.Cu")
		(at 420.624 -150.876 90)
		(property "Reference" "C2L15"
			(at 0 0 90)
			(layer "B.SilkS")
			(hide yes)
			(effects
				(font
					(size 1.27 1.27)
				)
				(justify mirror)
			)
		)
		(property "Value" ""
			(at 0 0 90)
			(layer "B.Fab")
			(effects
				(font
					(size 1.27 1.27)
				)
				(justify mirror)
			)
		)
		(duplicate_pad_numbers_are_jumpers no)
		(fp_poly
			(pts
				(xy -0.3048 -0.1016) (xy -0.3048 0.9906) (xy 0.3048 0.9906) (xy 0.3048 -0.1016)
			)
			(stroke
				(width 0)
				(type default)
			)
			(fill no)
			(layer "B.CrtYd")
		)
		(fp_line
			(start 0.3048 -0.1016)
			(end 0.3048 0.9906)
			(stroke
				(width 0.1)
				(type default)
			)
			(layer "B.Fab")
		)
		(fp_line
			(start -0.3048 -0.1016)
			(end 0.3048 -0.1016)
			(stroke
				(width 0.1)
				(type default)
			)
			(layer "B.Fab")
		)
		(fp_line
			(start 0.3048 0.9906)
			(end -0.3048 0.9906)
			(stroke
				(width 0.1)
				(type default)
			)
			(layer "B.Fab")
		)
		(fp_line
			(start -0.3048 0.9906)
			(end -0.3048 -0.1016)
			(stroke
				(width 0.1)
				(type default)
			)
			(layer "B.Fab")
		)
		(pad "1" smd rect
			(at 0 0 270)
			(size 0.508 0.508)
			(layers "B.Cu" "B.Mask" "B.Paste")
			(net "SATA6G_PCH_PCIE_UP_SATA_RXP<2>")
		)
		(pad "2" smd rect
			(at 0 0.889 270)
			(size 0.508 0.508)
			(layers "B.Cu" "B.Mask" "B.Paste")
			(net "SATA6G_P2_RX_C_DP")
		)
		(zone
			(layer "B.Cu")
			(hatch none 0.5)
			(connect_pads
				(clearance 0)
			)
			(min_thickness 0.25)
			(keepout
				(tracks allowed)
				(vias not_allowed)
				(pads allowed)
				(copperpour not_allowed)
				(footprints allowed)
			)
			(placement
				(enabled no)
				(sheetname "")
			)
			(fill
				(thermal_gap 0.5)
				(thermal_bridge_width 0.5)
				(island_removal_mode 0)
			)
			(polygon
				(pts
					(xy 420.878 -151.13) (xy 420.878 -150.622) (xy 421.259 -150.622) (xy 421.259 -151.13)
				)
			)
		)
		(zone
			(layer "B.Cu")
			(hatch none 0.5)
			(connect_pads
				(clearance 0)
			)
			(min_thickness 0.25)
			(keepout
				(tracks not_allowed)
				(vias allowed)
				(pads allowed)
				(copperpour not_allowed)
				(footprints allowed)
			)
			(placement
				(enabled no)
				(sheetname "")
			)
			(fill
				(thermal_gap 0.5)
				(thermal_bridge_width 0.5)
				(island_removal_mode 0)
			)
			(polygon
				(pts
					(xy 421.259 -151.13) (xy 421.259 -150.622) (xy 420.878 -150.622) (xy 420.878 -151.13)
				)
			)
		)
	)
	(footprint ""
		(layer "B.Cu")
		(at 101.3968 -3.3528 90)
		(property "Reference" "C5G89"
			(at -1.14681 0.76708 180)
			(unlocked yes)
			(layer "B.SilkS")
			(effects
				(font
					(size 0.7874 0.5842)
					(thickness 0.1524)
				)
				(justify mirror)
			)
		)
		(property "Value" ""
			(at 0 0 90)
			(layer "B.Fab")
			(effects
				(font
					(size 1.27 1.27)
				)
				(justify mirror)
			)
		)
		(duplicate_pad_numbers_are_jumpers no)
		(fp_rect
			(start -0.4953 -0.2032)
			(end 0.4953 1.6002)
			(stroke
				(width 0)
				(type default)
			)
			(fill no)
			(layer "B.CrtYd")
		)
		(fp_line
			(start 0.4953 -0.2032)
			(end -0.4953 -0.2032)
			(stroke
				(width 0.1)
				(type default)
			)
			(layer "B.Fab")
		)
		(fp_line
			(start -0.4953 -0.2032)
			(end -0.4953 1.6002)
			(stroke
				(width 0.1)
				(type default)
			)
			(layer "B.Fab")
		)
		(fp_line
			(start 0.4953 1.6002)
			(end 0.4953 -0.2032)
			(stroke
				(width 0.1)
				(type default)
			)
			(layer "B.Fab")
		)
		(fp_line
			(start -0.4953 1.6002)
			(end 0.4953 1.6002)
			(stroke
				(width 0.1)
				(type default)
			)
			(layer "B.Fab")
		)
		(pad "1" smd rect
			(at 0 0 270)
			(size 0.762 0.889)
			(layers "B.Cu" "B.Mask" "B.Paste")
			(net "PVDDQ_GHJ")
		)
		(pad "2" smd rect
			(at 0 1.397 270)
			(size 0.762 0.889)
			(layers "B.Cu" "B.Mask" "B.Paste")
			(net "GND")
		)
		(zone
			(layer "B.Cu")
			(hatch none 0.5)
			(connect_pads
				(clearance 0)
			)
			(min_thickness 0.25)
			(keepout
				(tracks not_allowed)
				(vias allowed)
				(pads allowed)
				(copperpour not_allowed)
				(footprints allowed)
			)
			(placement
				(enabled no)
				(sheetname "")
			)
			(fill
				(thermal_gap 0.5)
				(thermal_bridge_width 0.5)
				(island_removal_mode 0)
			)
			(polygon
				(pts
					(xy 101.8413 -2.9718) (xy 102.3493 -2.9718) (xy 102.3493 -3.7338) (xy 101.8413 -3.7338)
				)
			)
		)
	)
	(footprint ""
		(layer "B.Cu")
		(at 446.381632 -32.4485 90)
		(property "Reference" "R25W1"
			(at 0 0 90)
			(layer "B.SilkS")
			(hide yes)
			(effects
				(font
					(size 1.27 1.27)
				)
				(justify mirror)
			)
		)
		(property "Value" "*"
			(at -0.064008 -4.108196 90)
			(unlocked yes)
			(layer "B.Fab")
			(hide yes)
			(effects
				(font
					(size 1.27 1.016)
					(thickness 0.1524)
				)
				(justify mirror)
			)
		)
		(property "Device Type" "120R2F-GP_RCL_GP-120R2F-GP,64.A"
			(at -0.064008 -5.632196 90)
			(unlocked yes)
			(layer "B.Fab")
			(hide yes)
			(effects
				(font
					(size 1.27 1.016)
					(thickness 0.1524)
				)
				(justify mirror)
			)
		)
		(duplicate_pad_numbers_are_jumpers no)
		(fp_line
			(start 0.508 -0.9398)
			(end 0.508 0.9398)
			(stroke
				(width 0.1524)
				(type default)
			)
			(layer "B.SilkS")
		)
		(fp_line
			(start -0.508 -0.9398)
			(end 0.508 -0.9398)
			(stroke
				(width 0.1524)
				(type default)
			)
			(layer "B.SilkS")
		)
		(fp_rect
			(start 0.508 0.9398)
			(end -0.508 -0.9398)
			(stroke
				(width 0)
				(type default)
			)
			(fill no)
			(layer "B.CrtYd")
		)
		(fp_rect
			(start 0.508 0.9398)
			(end -0.508 -0.9398)
			(stroke
				(width 0)
				(type default)
			)
			(fill no)
			(layer "B.Fab")
		)
		(pad "1" smd custom
			(at 0 -0.4445 270)
			(size 0.1397 0.1397)
			(layers "B.Cu" "B.Mask" "B.Paste")
			(net "GND")
			(options
				(clearance outline)
				(anchor circle)
			)
			(primitives
				(gr_poly
					(pts
						(arc
							(start -0.1778 0.2794)
							(mid -0.249642 0.249642)
							(end -0.2794 0.1778)
						)
						(arc
							(start -0.2794 -0.1778)
							(mid -0.249642 -0.249642)
							(end -0.1778 -0.2794)
						)
						(arc
							(start 0.1778 -0.2794)
							(mid 0.249642 -0.249642)
							(end 0.2794 -0.1778)
						)
						(arc
							(start 0.2794 0.1778)
							(mid 0.249642 0.249642)
							(end 0.1778 0.2794)
						)
					)
					(width 0)
					(fill yes)
				)
			)
		)
		(pad "2" smd custom
			(at 0 0.4445 270)
			(size 0.1397 0.1397)
			(layers "B.Cu" "B.Mask" "B.Paste")
			(net "BMC_M_CKE")
			(options
				(clearance outline)
				(anchor circle)
			)
			(primitives
				(gr_poly
					(pts
						(arc
							(start -0.1778 0.2794)
							(mid -0.249642 0.249642)
							(end -0.2794 0.1778)
						)
						(arc
							(start -0.2794 -0.1778)
							(mid -0.249642 -0.249642)
							(end -0.1778 -0.2794)
						)
						(arc
							(start 0.1778 -0.2794)
							(mid 0.249642 -0.249642)
							(end 0.2794 -0.1778)
						)
						(arc
							(start 0.2794 0.1778)
							(mid 0.249642 0.249642)
							(end 0.1778 0.2794)
						)
					)
					(width 0)
					(fill yes)
				)
			)
		)
	)
	(footprint ""
		(layer "B.Cu")
		(at 3.893312 -20.237196 90)
		(property "Reference" "C9T4"
			(at 0 0 90)
			(layer "B.SilkS")
			(hide yes)
			(effects
				(font
					(size 1.27 1.27)
				)
				(justify mirror)
			)
		)
		(property "Value" ""
			(at 0 0 90)
			(layer "B.Fab")
			(effects
				(font
					(size 1.27 1.27)
				)
				(justify mirror)
			)
		)
		(duplicate_pad_numbers_are_jumpers no)
		(fp_rect
			(start -0.7239 -0.2159)
			(end 0.7239 1.9939)
			(stroke
				(width 0)
				(type default)
			)
			(fill no)
			(layer "B.CrtYd")
		)
		(fp_line
			(start 0.7239 -0.2159)
			(end 0.7239 1.9939)
			(stroke
				(width 0.1)
				(type default)
			)
			(layer "B.Fab")
		)
		(fp_line
			(start -0.7239 -0.2159)
			(end 0.7239 -0.2159)
			(stroke
				(width 0.1)
				(type default)
			)
			(layer "B.Fab")
		)
		(fp_line
			(start 0.7239 1.9939)
			(end -0.7239 1.9939)
			(stroke
				(width 0.1)
				(type default)
			)
			(layer "B.Fab")
		)
		(fp_line
			(start -0.7239 1.9939)
			(end -0.7239 -0.2159)
			(stroke
				(width 0.1)
				(type default)
			)
			(layer "B.Fab")
		)
		(pad "1" smd rect
			(at 0 0 270)
			(size 1.27 1.016)
			(layers "B.Cu" "B.Mask" "B.Paste")
			(net "VR_FET_SW_P12V_STBY_PVDDQ_GHJ")
		)
		(pad "2" smd rect
			(at 0 1.778 270)
			(size 1.27 1.016)
			(layers "B.Cu" "B.Mask" "B.Paste")
			(net "GND")
		)
		(zone
			(layer "B.Cu")
			(hatch none 0.5)
			(connect_pads
				(clearance 0)
			)
			(min_thickness 0.25)
			(keepout
				(tracks not_allowed)
				(vias allowed)
				(pads allowed)
				(copperpour not_allowed)
				(footprints allowed)
			)
			(placement
				(enabled no)
				(sheetname "")
			)
			(fill
				(thermal_gap 0.5)
				(thermal_bridge_width 0.5)
				(island_removal_mode 0)
			)
			(polygon
				(pts
					(xy 4.401312 -19.602196) (xy 5.163312 -19.602196) (xy 5.163312 -20.872196) (xy 4.401312 -20.872196)
				)
			)
		)
	)
	(footprint ""
		(layer "B.Cu")
		(at 398.860518 -61.894974 -90)
		(property "Reference" "R1W29"
			(at 0.8382 -0.67818 270)
			(unlocked yes)
			(layer "B.SilkS")
			(effects
				(font
					(size 0.4064 0.254)
					(thickness 0.1524)
				)
				(justify left mirror)
			)
		)
		(property "Value" ""
			(at 0 0 90)
			(layer "B.Fab")
			(effects
				(font
					(size 1.27 1.27)
				)
				(justify mirror)
			)
		)
		(duplicate_pad_numbers_are_jumpers no)
		(fp_poly
			(pts
				(xy 0.2794 -0.1016) (xy -0.2794 -0.1016) (xy -0.2794 0.9906) (xy 0.2794 0.9906)
			)
			(stroke
				(width 0)
				(type default)
			)
			(fill no)
			(layer "B.CrtYd")
		)
		(fp_line
			(start -0.2794 0.9906)
			(end -0.2794 -0.1016)
			(stroke
				(width 0.1)
				(type default)
			)
			(layer "B.Fab")
		)
		(fp_line
			(start 0.2794 0.9906)
			(end -0.2794 0.9906)
			(stroke
				(width 0.1)
				(type default)
			)
			(layer "B.Fab")
		)
		(fp_line
			(start -0.2794 -0.1016)
			(end 0.2794 -0.1016)
			(stroke
				(width 0.1)
				(type default)
			)
			(layer "B.Fab")
		)
		(fp_line
			(start 0.2794 -0.1016)
			(end 0.2794 0.9906)
			(stroke
				(width 0.1)
				(type default)
			)
			(layer "B.Fab")
		)
		(pad "1" smd rect
			(at 0 0 90)
			(size 0.508 0.508)
			(layers "B.Cu" "B.Mask" "B.Paste")
			(net "RST_BMC_SYSRST_BTN_OUT_B_N")
		)
		(pad "2" smd rect
			(at 0 0.889 90)
			(size 0.508 0.508)
			(layers "B.Cu" "B.Mask" "B.Paste")
			(net "RST_BMC_SYSRST_BTN_OUT_B_R1_N")
		)
		(zone
			(layer "B.Cu")
			(hatch none 0.5)
			(connect_pads
				(clearance 0)
			)
			(min_thickness 0.25)
			(keepout
				(tracks not_allowed)
				(vias allowed)
				(pads allowed)
				(copperpour not_allowed)
				(footprints allowed)
			)
			(placement
				(enabled no)
				(sheetname "")
			)
			(fill
				(thermal_gap 0.5)
				(thermal_bridge_width 0.5)
				(island_removal_mode 0)
			)
			(polygon
				(pts
					(xy 398.225518 -61.640974) (xy 398.225518 -62.148974) (xy 398.606518 -62.148974) (xy 398.606518 -61.640974)
				)
			)
		)
		(zone
			(layer "B.Cu")
			(hatch none 0.5)
			(connect_pads
				(clearance 0)
			)
			(min_thickness 0.25)
			(keepout
				(tracks allowed)
				(vias not_allowed)
				(pads allowed)
				(copperpour not_allowed)
				(footprints allowed)
			)
			(placement
				(enabled no)
				(sheetname "")
			)
			(fill
				(thermal_gap 0.5)
				(thermal_bridge_width 0.5)
				(island_removal_mode 0)
			)
			(polygon
				(pts
					(xy 398.606518 -61.640974) (xy 398.606518 -62.148974) (xy 398.225518 -62.148974) (xy 398.225518 -61.640974)
				)
			)
		)
	)
	(footprint ""
		(layer "B.Cu")
		(at 259.4102 -144.977612 90)
		(property "Reference" "C5L14"
			(at 0 0 90)
			(layer "B.SilkS")
			(hide yes)
			(effects
				(font
					(size 1.27 1.27)
				)
				(justify mirror)
			)
		)
		(property "Value" ""
			(at 0 0 90)
			(layer "B.Fab")
			(effects
				(font
					(size 1.27 1.27)
				)
				(justify mirror)
			)
		)
		(duplicate_pad_numbers_are_jumpers no)
		(fp_rect
			(start -0.7239 -0.2159)
			(end 0.7239 1.9939)
			(stroke
				(width 0)
				(type default)
			)
			(fill no)
			(layer "B.CrtYd")
		)
		(fp_line
			(start 0.7239 -0.2159)
			(end 0.7239 1.9939)
			(stroke
				(width 0.1)
				(type default)
			)
			(layer "B.Fab")
		)
		(fp_line
			(start -0.7239 -0.2159)
			(end 0.7239 -0.2159)
			(stroke
				(width 0.1)
				(type default)
			)
			(layer "B.Fab")
		)
		(fp_line
			(start 0.7239 1.9939)
			(end -0.7239 1.9939)
			(stroke
				(width 0.1)
				(type default)
			)
			(layer "B.Fab")
		)
		(fp_line
			(start -0.7239 1.9939)
			(end -0.7239 -0.2159)
			(stroke
				(width 0.1)
				(type default)
			)
			(layer "B.Fab")
		)
		(pad "1" smd rect
			(at 0 0 270)
			(size 1.27 1.016)
			(layers "B.Cu" "B.Mask" "B.Paste")
			(net "PVDDQ_DEF")
		)
		(pad "2" smd rect
			(at 0 1.778 270)
			(size 1.27 1.016)
			(layers "B.Cu" "B.Mask" "B.Paste")
			(net "GND")
		)
		(zone
			(layer "B.Cu")
			(hatch none 0.5)
			(connect_pads
				(clearance 0)
			)
			(min_thickness 0.25)
			(keepout
				(tracks not_allowed)
				(vias allowed)
				(pads allowed)
				(copperpour not_allowed)
				(footprints allowed)
			)
			(placement
				(enabled no)
				(sheetname "")
			)
			(fill
				(thermal_gap 0.5)
				(thermal_bridge_width 0.5)
				(island_removal_mode 0)
			)
			(polygon
				(pts
					(xy 259.9182 -144.342612) (xy 260.6802 -144.342612) (xy 260.6802 -145.612612) (xy 259.9182 -145.612612)
				)
			)
		)
	)
)
